(kicad_pcb
	(version 20260206)
	(generator "pcbnew")
	(generator_version "10.0")
	(general
		(thickness 1.6)
		(legacy_teardrops no)
	)
	(paper "A4")
	(title_block
		(title "baseboard — 13948-1b.1110WZS1818.brd")
		(comment 1 "Honey Badger (Wiwynn) / footprints 211-217 of 2523")
	)
	(layers
		(0 "F.Cu" signal "TOP")
		(4 "In1.Cu" signal "L2GND")
		(6 "In2.Cu" signal "L3")
		(8 "In3.Cu" signal "L4VCC")
		(10 "In4.Cu" signal "L5VCC")
		(12 "In5.Cu" signal "L6")
		(14 "In6.Cu" signal "L7GND")
		(2 "B.Cu" signal "BOTTOM")
		(9 "F.Adhes" user "F.Adhesive")
		(11 "B.Adhes" user "B.Adhesive")
		(13 "F.Paste" user "Package Geometry/Pastemask Top")
		(15 "B.Paste" user "Package Geometry/Pastemask Bottom")
		(5 "F.SilkS" user "Ref Des/Silkscreen Top")
		(7 "B.SilkS" user "Ref Des/Silkscreen Bottom")
		(1 "F.Mask" user "Board Geometry/Soldermask Top")
		(3 "B.Mask" user "Board Geometry/Soldermask Bottom")
		(17 "Dwgs.User" user "User.Drawings")
		(19 "Cmts.User" user "User.Comments")
		(21 "Eco1.User" user "User.Eco1")
		(23 "Eco2.User" user "User.Eco2")
		(25 "Edge.Cuts" user "Board Geometry/Outline")
		(27 "Margin" user)
		(31 "F.CrtYd" user "Package Geometry/Place Bound Top")
		(29 "B.CrtYd" user "Package Geometry/Place Bound Bottom")
		(35 "F.Fab" user "Ref Des/Assembly Top")
		(33 "B.Fab" user "Ref Des/Assembly Bottom")
	)
	(footprint ""
		(layer "F.Cu")
		(at 318.008 -163.322 -90)
		(property "Reference" "R262"
			(at 0 0 270)
			(layer "F.SilkS")
			(hide yes)
			(effects
				(font
					(size 1.27 1.27)
				)
			)
		)
		(property "Value" "10KR2F-2-GP"
			(at 0.064008 -3.993896 270)
			(unlocked yes)
			(layer "F.Fab")
			(hide yes)
			(effects
				(font
					(size 1.016 1.016)
					(thickness 0.1524)
				)
			)
		)
		(property "Device Type" "R402H16"
			(at 0.064008 -5.517896 270)
			(unlocked yes)
			(layer "F.Fab")
			(hide yes)
			(effects
				(font
					(size 1.016 1.016)
					(thickness 0.1524)
				)
			)
		)
		(duplicate_pad_numbers_are_jumpers no)
		(fp_line
			(start -0.508 -0.9398)
			(end -0.508 0.9398)
			(stroke
				(width 0.1524)
				(type default)
			)
			(layer "F.SilkS")
		)
		(fp_line
			(start 0.508 -0.9398)
			(end -0.508 -0.9398)
			(stroke
				(width 0.1524)
				(type default)
			)
			(layer "F.SilkS")
		)
		(fp_rect
			(start -0.508 0.9398)
			(end 0.508 -0.9398)
			(stroke
				(width 0)
				(type default)
			)
			(fill no)
			(layer "F.CrtYd")
		)
		(fp_rect
			(start -0.508 0.9398)
			(end 0.508 -0.9398)
			(stroke
				(width 0)
				(type default)
			)
			(fill no)
			(layer "F.Fab")
		)
		(pad "1" smd custom
			(at 0 -0.4445 270)
			(size 0.1397 0.1397)
			(layers "F.Cu" "F.Mask" "F.Paste")
			(net "P3V3_STBY")
			(options
				(clearance outline)
				(anchor circle)
			)
			(primitives
				(gr_poly
					(pts
						(arc
							(start -0.1778 -0.2794)
							(mid -0.249642 -0.249642)
							(end -0.2794 -0.1778)
						)
						(arc
							(start -0.2794 0.1778)
							(mid -0.249642 0.249642)
							(end -0.1778 0.2794)
						)
						(arc
							(start 0.1778 0.2794)
							(mid 0.249642 0.249642)
							(end 0.2794 0.1778)
						)
						(arc
							(start 0.2794 -0.1778)
							(mid 0.249642 -0.249642)
							(end 0.1778 -0.2794)
						)
					)
					(width 0)
					(fill yes)
				)
			)
		)
		(pad "2" smd custom
			(at 0 0.4445 270)
			(size 0.1397 0.1397)
			(layers "F.Cu" "F.Mask" "F.Paste")
			(net "PU_BMC0_SCL12")
			(options
				(clearance outline)
				(anchor circle)
			)
			(primitives
				(gr_poly
					(pts
						(arc
							(start -0.1778 -0.2794)
							(mid -0.249642 -0.249642)
							(end -0.2794 -0.1778)
						)
						(arc
							(start -0.2794 0.1778)
							(mid -0.249642 0.249642)
							(end -0.1778 0.2794)
						)
						(arc
							(start 0.1778 0.2794)
							(mid 0.249642 0.249642)
							(end 0.2794 0.1778)
						)
						(arc
							(start 0.2794 -0.1778)
							(mid 0.249642 -0.249642)
							(end 0.1778 -0.2794)
						)
					)
					(width 0)
					(fill yes)
				)
			)
		)
	)
	(footprint ""
		(layer "F.Cu")
		(at 112.846612 -222.885)
		(property "Reference" "SR882"
			(at 0 0 0)
			(layer "F.SilkS")
			(hide yes)
			(effects
				(font
					(size 1.27 1.27)
				)
			)
		)
		(property "Value" "0R2J-2-GP"
			(at 0.064008 -3.993896 0)
			(unlocked yes)
			(layer "F.Fab")
			(hide yes)
			(effects
				(font
					(size 1.016 1.016)
					(thickness 0.1524)
				)
			)
		)
		(property "Device Type" "R402H16"
			(at 0.064008 -5.517896 0)
			(unlocked yes)
			(layer "F.Fab")
			(hide yes)
			(effects
				(font
					(size 1.016 1.016)
					(thickness 0.1524)
				)
			)
		)
		(duplicate_pad_numbers_are_jumpers no)
		(fp_line
			(start -0.508 -0.9398)
			(end -0.508 0.9398)
			(stroke
				(width 0.1524)
				(type default)
			)
			(layer "F.SilkS")
		)
		(fp_line
			(start 0.508 -0.9398)
			(end -0.508 -0.9398)
			(stroke
				(width 0.1524)
				(type default)
			)
			(layer "F.SilkS")
		)
		(fp_rect
			(start -0.508 0.9398)
			(end 0.508 -0.9398)
			(stroke
				(width 0)
				(type default)
			)
			(fill no)
			(layer "F.CrtYd")
		)
		(fp_rect
			(start -0.508 0.9398)
			(end 0.508 -0.9398)
			(stroke
				(width 0)
				(type default)
			)
			(fill no)
			(layer "F.Fab")
		)
		(pad "1" smd custom
			(at 0 -0.4445)
			(size 0.1397 0.1397)
			(layers "F.Cu" "F.Mask" "F.Paste")
			(net "SAS_HDD_CONN_SER_TX8_N")
			(options
				(clearance outline)
				(anchor circle)
			)
			(primitives
				(gr_poly
					(pts
						(arc
							(start -0.1778 -0.2794)
							(mid -0.249642 -0.249642)
							(end -0.2794 -0.1778)
						)
						(arc
							(start -0.2794 0.1778)
							(mid -0.249642 0.249642)
							(end -0.1778 0.2794)
						)
						(arc
							(start 0.1778 0.2794)
							(mid 0.249642 0.249642)
							(end 0.2794 0.1778)
						)
						(arc
							(start 0.2794 -0.1778)
							(mid 0.249642 -0.249642)
							(end 0.1778 -0.2794)
						)
					)
					(width 0)
					(fill yes)
				)
			)
		)
		(pad "2" smd custom
			(at 0 0.4445)
			(size 0.1397 0.1397)
			(layers "F.Cu" "F.Mask" "F.Paste")
			(net "SAS_HDD_CONN_TX8_N")
			(options
				(clearance outline)
				(anchor circle)
			)
			(primitives
				(gr_poly
					(pts
						(arc
							(start -0.1778 -0.2794)
							(mid -0.249642 -0.249642)
							(end -0.2794 -0.1778)
						)
						(arc
							(start -0.2794 0.1778)
							(mid -0.249642 0.249642)
							(end -0.1778 0.2794)
						)
						(arc
							(start 0.1778 0.2794)
							(mid 0.249642 0.249642)
							(end 0.2794 0.1778)
						)
						(arc
							(start 0.2794 -0.1778)
							(mid 0.249642 -0.249642)
							(end 0.1778 -0.2794)
						)
					)
					(width 0)
					(fill yes)
				)
			)
		)
	)
	(footprint ""
		(layer "F.Cu")
		(at 333.912718 -146.662648 -90)
		(property "Reference" "C318"
			(at 0 0 270)
			(layer "F.SilkS")
			(hide yes)
			(effects
				(font
					(size 1.27 1.27)
				)
			)
		)
		(property "Value" "SC1U6D3V3KX-2GP"
			(at 0 -2.8194 270)
			(unlocked yes)
			(layer "F.Fab")
			(hide yes)
			(effects
				(font
					(size 1.016 1.016)
					(thickness 0.1524)
				)
			)
		)
		(property "Device Type" "C603H36"
			(at 0 -4.3434 270)
			(unlocked yes)
			(layer "F.Fab")
			(hide yes)
			(effects
				(font
					(size 1.016 1.016)
					(thickness 0.1524)
				)
			)
		)
		(duplicate_pad_numbers_are_jumpers no)
		(fp_line
			(start 0.508 0)
			(end -0.508 0)
			(stroke
				(width 0.2032)
				(type default)
			)
			(layer "F.SilkS")
		)
		(fp_rect
			(start -0.5842 1.3335)
			(end 0.5842 -1.3335)
			(stroke
				(width 0)
				(type default)
			)
			(fill no)
			(layer "F.CrtYd")
		)
		(fp_rect
			(start -0.5842 1.3335)
			(end 0.5842 -1.3335)
			(stroke
				(width 0)
				(type default)
			)
			(fill no)
			(layer "F.Fab")
		)
		(pad "1" smd custom
			(at 0 -0.762 270)
			(size 0.2159 0.2159)
			(layers "F.Cu" "F.Mask" "F.Paste")
			(net "USB_RESET_N")
			(options
				(clearance outline)
				(anchor circle)
			)
			(primitives
				(gr_poly
					(pts
						(arc
							(start -0.3302 -0.4318)
							(mid -0.402042 -0.402042)
							(end -0.4318 -0.3302)
						)
						(arc
							(start -0.4318 0.3302)
							(mid -0.402042 0.402042)
							(end -0.3302 0.4318)
						)
						(arc
							(start 0.3302 0.4318)
							(mid 0.402042 0.402042)
							(end 0.4318 0.3302)
						)
						(arc
							(start 0.4318 -0.3302)
							(mid 0.402042 -0.402042)
							(end 0.3302 -0.4318)
						)
					)
					(width 0)
					(fill yes)
				)
			)
		)
		(pad "2" smd custom
			(at 0 0.762 270)
			(size 0.2159 0.2159)
			(layers "F.Cu" "F.Mask" "F.Paste")
			(net "GND")
			(options
				(clearance outline)
				(anchor circle)
			)
			(primitives
				(gr_poly
					(pts
						(arc
							(start -0.3302 -0.4318)
							(mid -0.402042 -0.402042)
							(end -0.4318 -0.3302)
						)
						(arc
							(start -0.4318 0.3302)
							(mid -0.402042 0.402042)
							(end -0.3302 0.4318)
						)
						(arc
							(start 0.3302 0.4318)
							(mid 0.402042 0.402042)
							(end 0.4318 0.3302)
						)
						(arc
							(start 0.4318 -0.3302)
							(mid 0.402042 -0.402042)
							(end 0.3302 -0.4318)
						)
					)
					(width 0)
					(fill yes)
				)
			)
		)
	)
	(footprint ""
		(layer "F.Cu")
		(at 164.153596 -147.720812 90)
		(property "Reference" "SU62"
			(at 0 0 90)
			(layer "F.SilkS")
			(hide yes)
			(effects
				(font
					(size 1.27 1.27)
				)
			)
		)
		(property "Value" "PCA9306DCTT-GP"
			(at 0 -11.6332 90)
			(unlocked yes)
			(layer "F.Fab")
			(hide yes)
			(effects
				(font
					(size 1.016 1.016)
					(thickness 0.1524)
				)
			)
		)
		(property "Device Type" "SSOIC8H52"
			(at 0 -13.1572 90)
			(unlocked yes)
			(layer "F.Fab")
			(hide yes)
			(effects
				(font
					(size 1.016 1.016)
					(thickness 0.1524)
				)
			)
		)
		(duplicate_pad_numbers_are_jumpers no)
		(fp_line
			(start 1.0668 -0.5842)
			(end 1.0668 0.5842)
			(stroke
				(width 0.1524)
				(type default)
			)
			(layer "F.SilkS")
		)
		(fp_line
			(start -1.7018 -0.5842)
			(end 1.0668 -0.5842)
			(stroke
				(width 0.1524)
				(type default)
			)
			(layer "F.SilkS")
		)
		(fp_line
			(start -1.7018 -0.5842)
			(end -1.7018 2.286)
			(stroke
				(width 0.1524)
				(type default)
			)
			(layer "F.SilkS")
		)
		(fp_line
			(start -1.397 0)
			(end -1.7018 -0.3048)
			(stroke
				(width 0.1524)
				(type default)
			)
			(layer "F.SilkS")
		)
		(fp_line
			(start -1.397 0)
			(end -1.7018 0.3048)
			(stroke
				(width 0.1524)
				(type default)
			)
			(layer "F.SilkS")
		)
		(fp_line
			(start 1.0668 0.5842)
			(end -1.524 0.5842)
			(stroke
				(width 0.1524)
				(type default)
			)
			(layer "F.SilkS")
		)
		(fp_line
			(start -1.524 0.5842)
			(end -1.524 2.286)
			(stroke
				(width 0.508)
				(type default)
			)
			(layer "F.SilkS")
		)
		(fp_poly
			(pts
				(xy -1.1684 -0.5842) (xy 1.0668 -0.5842) (xy 1.0668 0.5842) (xy -1.1684 0.5842)
			)
			(stroke
				(width 0)
				(type default)
			)
			(fill yes)
			(layer "F.SilkS")
		)
		(fp_poly
			(pts
				(xy -1.778 2.54) (xy 1.778 2.54) (xy 1.778 -2.54) (xy -1.778 -2.54)
			)
			(stroke
				(width 0)
				(type default)
			)
			(fill no)
			(layer "F.CrtYd")
		)
		(fp_poly
			(pts
				(xy -1.778 -2.54) (xy 1.778 -2.54) (xy 1.778 2.54) (xy -1.778 2.54)
			)
			(stroke
				(width 0)
				(type default)
			)
			(fill no)
			(layer "F.Fab")
		)
		(pad "1" smd rect
			(at -0.97536 1.6256 90)
			(size 0.3556 1.524)
			(layers "F.Cu" "F.Mask" "F.Paste")
			(net "GND")
		)
		(pad "2" smd rect
			(at -0.32512 1.6256 90)
			(size 0.3556 1.524)
			(layers "F.Cu" "F.Mask" "F.Paste")
			(net "P1V8_C")
		)
		(pad "3" smd rect
			(at 0.32512 1.6256 90)
			(size 0.3556 1.524)
			(layers "F.Cu" "F.Mask" "F.Paste")
			(net "IOC_SCL_4")
		)
		(pad "4" smd rect
			(at 0.97536 1.6256 90)
			(size 0.3556 1.524)
			(layers "F.Cu" "F.Mask" "F.Paste")
			(net "IOC_SDA_4")
		)
		(pad "5" smd rect
			(at 0.97536 -1.6256 90)
			(size 0.3556 1.524)
			(layers "F.Cu" "F.Mask" "F.Paste")
			(net "IOC_P3V3_SDA_14")
		)
		(pad "6" smd rect
			(at 0.32512 -1.6256 90)
			(size 0.3556 1.524)
			(layers "F.Cu" "F.Mask" "F.Paste")
			(net "IOC_P3V3_SCL_14")
		)
		(pad "7" smd rect
			(at -0.32512 -1.6256 90)
			(size 0.3556 1.524)
			(layers "F.Cu" "F.Mask" "F.Paste")
			(net "IOC_I2C_VREF")
		)
		(pad "8" smd rect
			(at -0.97536 -1.6256 90)
			(size 0.3556 1.524)
			(layers "F.Cu" "F.Mask" "F.Paste")
			(net "IOC_I2C_VREF")
		)
	)
	(footprint ""
		(layer "F.Cu")
		(at 41.402 -178.943 180)
		(property "Reference" "SR1272"
			(at 0 0 180)
			(layer "F.SilkS")
			(hide yes)
			(effects
				(font
					(size 1.27 1.27)
				)
			)
		)
		(property "Value" "1KR2J-1-GP"
			(at 0.064008 -3.993896 180)
			(unlocked yes)
			(layer "F.Fab")
			(hide yes)
			(effects
				(font
					(size 1.016 1.016)
					(thickness 0.1524)
				)
			)
		)
		(property "Device Type" "R402H16"
			(at 0.064008 -5.517896 180)
			(unlocked yes)
			(layer "F.Fab")
			(hide yes)
			(effects
				(font
					(size 1.016 1.016)
					(thickness 0.1524)
				)
			)
		)
		(duplicate_pad_numbers_are_jumpers no)
		(fp_line
			(start 0.508 -0.9398)
			(end -0.508 -0.9398)
			(stroke
				(width 0.1524)
				(type default)
			)
			(layer "F.SilkS")
		)
		(fp_line
			(start -0.508 -0.9398)
			(end -0.508 0.9398)
			(stroke
				(width 0.1524)
				(type default)
			)
			(layer "F.SilkS")
		)
		(fp_rect
			(start -0.508 0.9398)
			(end 0.508 -0.9398)
			(stroke
				(width 0)
				(type default)
			)
			(fill no)
			(layer "F.CrtYd")
		)
		(fp_rect
			(start -0.508 0.9398)
			(end 0.508 -0.9398)
			(stroke
				(width 0)
				(type default)
			)
			(fill no)
			(layer "F.Fab")
		)
		(pad "1" smd custom
			(at 0 -0.4445 180)
			(size 0.1397 0.1397)
			(layers "F.Cu" "F.Mask" "F.Paste")
			(net "RST_BTN_R")
			(options
				(clearance outline)
				(anchor circle)
			)
			(primitives
				(gr_poly
					(pts
						(arc
							(start -0.1778 -0.2794)
							(mid -0.249642 -0.249642)
							(end -0.2794 -0.1778)
						)
						(arc
							(start -0.2794 0.1778)
							(mid -0.249642 0.249642)
							(end -0.1778 0.2794)
						)
						(arc
							(start 0.1778 0.2794)
							(mid 0.249642 0.249642)
							(end 0.2794 0.1778)
						)
						(arc
							(start 0.2794 -0.1778)
							(mid 0.249642 -0.249642)
							(end 0.1778 -0.2794)
						)
					)
					(width 0)
					(fill yes)
				)
			)
		)
		(pad "2" smd custom
			(at 0 0.4445 180)
			(size 0.1397 0.1397)
			(layers "F.Cu" "F.Mask" "F.Paste")
			(net "P1V8_E")
			(options
				(clearance outline)
				(anchor circle)
			)
			(primitives
				(gr_poly
					(pts
						(arc
							(start -0.1778 -0.2794)
							(mid -0.249642 -0.249642)
							(end -0.2794 -0.1778)
						)
						(arc
							(start -0.2794 0.1778)
							(mid -0.249642 0.249642)
							(end -0.1778 0.2794)
						)
						(arc
							(start 0.1778 0.2794)
							(mid 0.249642 0.249642)
							(end 0.2794 0.1778)
						)
						(arc
							(start 0.2794 -0.1778)
							(mid 0.249642 -0.249642)
							(end 0.1778 -0.2794)
						)
					)
					(width 0)
					(fill yes)
				)
			)
		)
	)
	(footprint ""
		(layer "F.Cu")
		(at 194.818 -116.205)
		(property "Reference" "PR9020"
			(at 0 0 0)
			(layer "F.SilkS")
			(hide yes)
			(effects
				(font
					(size 1.27 1.27)
				)
			)
		)
		(property "Value" "0R2J-2-GP"
			(at 0.064008 -3.993896 0)
			(unlocked yes)
			(layer "F.Fab")
			(hide yes)
			(effects
				(font
					(size 1.016 1.016)
					(thickness 0.1524)
				)
			)
		)
		(property "Device Type" "R402H16"
			(at 0.064008 -5.517896 0)
			(unlocked yes)
			(layer "F.Fab")
			(hide yes)
			(effects
				(font
					(size 1.016 1.016)
					(thickness 0.1524)
				)
			)
		)
		(duplicate_pad_numbers_are_jumpers no)
		(fp_line
			(start -0.508 -0.9398)
			(end -0.508 0.9398)
			(stroke
				(width 0.1524)
				(type default)
			)
			(layer "F.SilkS")
		)
		(fp_line
			(start 0.508 -0.9398)
			(end -0.508 -0.9398)
			(stroke
				(width 0.1524)
				(type default)
			)
			(layer "F.SilkS")
		)
		(fp_rect
			(start -0.508 0.9398)
			(end 0.508 -0.9398)
			(stroke
				(width 0)
				(type default)
			)
			(fill no)
			(layer "F.CrtYd")
		)
		(fp_rect
			(start -0.508 0.9398)
			(end 0.508 -0.9398)
			(stroke
				(width 0)
				(type default)
			)
			(fill no)
			(layer "F.Fab")
		)
		(pad "1" smd custom
			(at 0 -0.4445)
			(size 0.1397 0.1397)
			(layers "F.Cu" "F.Mask" "F.Paste")
			(net "P1V8_E_PG")
			(options
				(clearance outline)
				(anchor circle)
			)
			(primitives
				(gr_poly
					(pts
						(arc
							(start -0.1778 -0.2794)
							(mid -0.249642 -0.249642)
							(end -0.2794 -0.1778)
						)
						(arc
							(start -0.2794 0.1778)
							(mid -0.249642 0.249642)
							(end -0.1778 0.2794)
						)
						(arc
							(start 0.1778 0.2794)
							(mid 0.249642 0.249642)
							(end 0.2794 0.1778)
						)
						(arc
							(start 0.2794 -0.1778)
							(mid 0.249642 -0.249642)
							(end 0.1778 -0.2794)
						)
					)
					(width 0)
					(fill yes)
				)
			)
		)
		(pad "2" smd custom
			(at 0 0.4445)
			(size 0.1397 0.1397)
			(layers "F.Cu" "F.Mask" "F.Paste")
			(net "P1V5_E_EN_R")
			(options
				(clearance outline)
				(anchor circle)
			)
			(primitives
				(gr_poly
					(pts
						(arc
							(start -0.1778 -0.2794)
							(mid -0.249642 -0.249642)
							(end -0.2794 -0.1778)
						)
						(arc
							(start -0.2794 0.1778)
							(mid -0.249642 0.249642)
							(end -0.1778 0.2794)
						)
						(arc
							(start 0.1778 0.2794)
							(mid 0.249642 0.249642)
							(end 0.2794 0.1778)
						)
						(arc
							(start 0.2794 -0.1778)
							(mid 0.249642 -0.249642)
							(end 0.1778 -0.2794)
						)
					)
					(width 0)
					(fill yes)
				)
			)
		)
	)
	(footprint ""
		(layer "F.Cu")
		(at 317.881 -50.165 90)
		(property "Reference" "C249"
			(at 0 0 90)
			(layer "F.SilkS")
			(hide yes)
			(effects
				(font
					(size 1.27 1.27)
				)
			)
		)
		(property "Value" "SCD1U16V2KX-3GP"
			(at 1.1811 -2.7051 90)
			(unlocked yes)
			(layer "F.Fab")
			(hide yes)
			(effects
				(font
					(size 1.016 1.016)
					(thickness 0.1524)
				)
			)
		)
		(property "Device Type" "C402H22"
			(at 1.1811 -4.2291 90)
			(unlocked yes)
			(layer "F.Fab")
			(hide yes)
			(effects
				(font
					(size 1.016 1.016)
					(thickness 0.1524)
				)
			)
		)
		(duplicate_pad_numbers_are_jumpers no)
		(fp_rect
			(start -0.4318 0.9525)
			(end 0.4318 -0.9525)
			(stroke
				(width 0)
				(type default)
			)
			(fill no)
			(layer "F.CrtYd")
		)
		(fp_rect
			(start -0.4318 0.9525)
			(end 0.4318 -0.9525)
			(stroke
				(width 0)
				(type default)
			)
			(fill no)
			(layer "F.Fab")
		)
		(pad "1" smd custom
			(at 0 -0.4445 90)
			(size 0.1524 0.1524)
			(layers "F.Cu" "F.Mask" "F.Paste")
			(net "P5V_STBY")
			(options
				(clearance outline)
				(anchor circle)
			)
			(primitives
				(gr_poly
					(pts
						(arc
							(start 0.3048 -0.2032)
							(mid 0.275042 -0.275042)
							(end 0.2032 -0.3048)
						)
						(arc
							(start -0.2032 -0.3048)
							(mid -0.275042 -0.275042)
							(end -0.3048 -0.2032)
						)
						(arc
							(start -0.3048 0.2032)
							(mid -0.275042 0.275042)
							(end -0.2032 0.3048)
						)
						(arc
							(start 0.2032 0.3048)
							(mid 0.275042 0.275042)
							(end 0.3048 0.2032)
						)
					)
					(width 0)
					(fill yes)
				)
			)
		)
		(pad "2" smd custom
			(at 0 0.4445 90)
			(size 0.1524 0.1524)
			(layers "F.Cu" "F.Mask" "F.Paste")
			(net "GND")
			(options
				(clearance outline)
				(anchor circle)
			)
			(primitives
				(gr_poly
					(pts
						(arc
							(start 0.3048 -0.2032)
							(mid 0.275042 -0.275042)
							(end 0.2032 -0.3048)
						)
						(arc
							(start -0.2032 -0.3048)
							(mid -0.275042 -0.275042)
							(end -0.3048 -0.2032)
						)
						(arc
							(start -0.3048 0.2032)
							(mid -0.275042 0.275042)
							(end -0.2032 0.3048)
						)
						(arc
							(start 0.2032 0.3048)
							(mid 0.275042 0.275042)
							(end 0.3048 0.2032)
						)
					)
					(width 0)
					(fill yes)
				)
			)
		)
	)
)
